# T6G (Grand Teton) — schematic netlist excerpt (pin names and nets, part order shuffled) for the footprints in the layout excerpt that follows; sources: Cadence DE-HDL packaged netlist, KiCad conversion of 04192023_DAF0TMB3IC0_F0TG_MB_C_brd_V02_OCP.brd

PR6556  Q_RES  0 5% CHIP  pkg 0402LF  page 363 : A = P0V9_RETIMER_CPU0_VOS1 ; B = P0V9_CPU0_RT_2D
R6329  Q_RES  10K 1% EMPTY  pkg 0402LF  page 178 : A = P3V3_AUX ; B = USB_HUB2_TI_GRSTZ_MRP_PROG_FUNC1

(kicad_pcb
	(version 20260206)
	(generator "pcbnew")
	(generator_version "10.0")
	(general
		(thickness 1.6)
		(legacy_teardrops no)
	)
	(paper "A4")
	(title_block
		(title "04192023_DAF0TMB3IC0_F0TG_MB_C_brd_V02_OCP.brd")
		(comment 1 "Grand Teton / footprints 1819-1820 of 8354")
	)
	(layers
		(0 "F.Cu" signal "TOP")
		(4 "In1.Cu" signal "GND")
		(6 "In2.Cu" signal "IN1")
		(8 "In3.Cu" signal "GND1")
		(10 "In4.Cu" signal "IN2")
		(12 "In5.Cu" signal "GND2")
		(14 "In6.Cu" signal "IN3")
		(16 "In7.Cu" signal "GND3")
		(18 "In8.Cu" signal "VCC")
		(20 "In9.Cu" signal "VCC1")
		(22 "In10.Cu" signal "GND4")
		(24 "In11.Cu" signal "IN4")
		(26 "In12.Cu" signal "GND5")
		(28 "In13.Cu" signal "IN5")
		(30 "In14.Cu" signal "GND6")
		(32 "In15.Cu" signal "IN6")
		(34 "In16.Cu" signal "GND7")
		(2 "B.Cu" signal "BOTTOM")
		(9 "F.Adhes" user "F.Adhesive")
		(11 "B.Adhes" user "B.Adhesive")
		(13 "F.Paste" user "Package Geometry/Pastemask Top")
		(15 "B.Paste" user "Package Geometry/Pastemask Bottom")
		(5 "F.SilkS" user "Ref Des/Silkscreen Top")
		(7 "B.SilkS" user "Ref Des/Silkscreen Bottom")
		(1 "F.Mask" user "Board Geometry/Soldermask Top")
		(3 "B.Mask" user "Board Geometry/Soldermask Bottom")
		(17 "Dwgs.User" user "User.Drawings")
		(19 "Cmts.User" user "User.Comments")
		(21 "Eco1.User" user "User.Eco1")
		(23 "Eco2.User" user "User.Eco2")
		(25 "Edge.Cuts" user "Board Geometry/Outline")
		(27 "Margin" user)
		(31 "F.CrtYd" user "Package Geometry/Place Bound Top")
		(29 "B.CrtYd" user "Package Geometry/Place Bound Bottom")
		(35 "F.Fab" user "Ref Des/Assembly Top")
		(33 "B.Fab" user "Ref Des/Assembly Bottom")
	)
	(footprint ""
		(layer "F.Cu")
		(at 441.446666 -401.04187 90)
		(property "Reference" "PR6556"
			(at 0 0 90)
			(layer "F.SilkS")
			(hide yes)
			(effects
				(font
					(size 1.27 1.27)
				)
			)
		)
		(property "Value" ""
			(at 0 0 90)
			(layer "F.Fab")
			(effects
				(font
					(size 1.27 1.27)
				)
			)
		)
		(duplicate_pad_numbers_are_jumpers no)
		(fp_line
			(start 0.7874 -0.4064)
			(end 0.7874 0.4064)
			(stroke
				(width 0.1524)
				(type default)
			)
			(layer "F.SilkS")
		)
		(fp_line
			(start -0.7874 -0.4064)
			(end 0.7874 -0.4064)
			(stroke
				(width 0.1524)
				(type default)
			)
			(layer "F.SilkS")
		)
		(fp_line
			(start -0.7874 -0.121666)
			(end -0.7874 -0.4064)
			(stroke
				(width 0.1524)
				(type default)
			)
			(layer "F.SilkS")
		)
		(fp_line
			(start 0.7874 0.4064)
			(end -0.28067 0.4064)
			(stroke
				(width 0.1524)
				(type default)
			)
			(layer "F.SilkS")
		)
		(fp_line
			(start -0.12065 -0.305054)
			(end -0.12065 -0.2794)
			(stroke
				(width 0.1)
				(type default)
			)
			(layer "F.Fab")
		)
		(fp_line
			(start -0.67945 -0.305054)
			(end -0.12065 -0.305054)
			(stroke
				(width 0.1)
				(type default)
			)
			(layer "F.Fab")
		)
		(fp_line
			(start 0.67945 -0.3048)
			(end 0.67945 0.3048)
			(stroke
				(width 0.1)
				(type default)
			)
			(layer "F.Fab")
		)
		(fp_line
			(start 0.12065 -0.3048)
			(end 0.67945 -0.3048)
			(stroke
				(width 0.1)
				(type default)
			)
			(layer "F.Fab")
		)
		(fp_line
			(start 0.12065 -0.2794)
			(end 0.12065 -0.3048)
			(stroke
				(width 0.1)
				(type default)
			)
			(layer "F.Fab")
		)
		(fp_line
			(start -0.12065 -0.2794)
			(end 0.12065 -0.2794)
			(stroke
				(width 0.1)
				(type default)
			)
			(layer "F.Fab")
		)
		(fp_line
			(start 0.120396 0.2794)
			(end -0.12065 0.2794)
			(stroke
				(width 0.1)
				(type default)
			)
			(layer "F.Fab")
		)
		(fp_line
			(start -0.12065 0.2794)
			(end -0.12065 0.3048)
			(stroke
				(width 0.1)
				(type default)
			)
			(layer "F.Fab")
		)
		(fp_line
			(start 0.67945 0.3048)
			(end 0.120396 0.3048)
			(stroke
				(width 0.1)
				(type default)
			)
			(layer "F.Fab")
		)
		(fp_line
			(start 0.120396 0.3048)
			(end 0.120396 0.2794)
			(stroke
				(width 0.1)
				(type default)
			)
			(layer "F.Fab")
		)
		(fp_line
			(start -0.12065 0.3048)
			(end -0.67945 0.3048)
			(stroke
				(width 0.1)
				(type default)
			)
			(layer "F.Fab")
		)
		(fp_line
			(start -0.67945 0.3048)
			(end -0.67945 -0.305054)
			(stroke
				(width 0.1)
				(type default)
			)
			(layer "F.Fab")
		)
		(pad "1" smd circle
			(at -0.40005 0 90)
			(size 0 0)
			(layers "F.Cu" "F.Mask" "F.Paste")
			(net "P0V9_RETIMER_CPU0_VOS1")
		)
		(pad "2" smd circle
			(at 0.40005 0 90)
			(size 0 0)
			(layers "F.Cu" "F.Mask" "F.Paste")
			(net "P0V9_CPU0_RT_2D")
		)
	)
	(footprint ""
		(layer "F.Cu")
		(at 100.342192 -31.795212 90)
		(property "Reference" "R6329"
			(at 0 0 90)
			(layer "F.SilkS")
			(hide yes)
			(effects
				(font
					(size 1.27 1.27)
				)
			)
		)
		(property "Value" ""
			(at 0 0 90)
			(layer "F.Fab")
			(effects
				(font
					(size 1.27 1.27)
				)
			)
		)
		(duplicate_pad_numbers_are_jumpers no)
		(fp_line
			(start 0.7874 -0.4064)
			(end 0.7874 0.4064)
			(stroke
				(width 0.1524)
				(type default)
			)
			(layer "F.SilkS")
		)
		(fp_line
			(start -0.7874 -0.4064)
			(end 0.7874 -0.4064)
			(stroke
				(width 0.1524)
				(type default)
			)
			(layer "F.SilkS")
		)
		(fp_line
			(start 0.7874 0.4064)
			(end -0.7874 0.4064)
			(stroke
				(width 0.1524)
				(type default)
			)
			(layer "F.SilkS")
		)
		(fp_line
			(start -0.7874 0.4064)
			(end -0.7874 -0.4064)
			(stroke
				(width 0.1524)
				(type default)
			)
			(layer "F.SilkS")
		)
		(fp_line
			(start -0.12065 -0.305054)
			(end -0.12065 -0.2794)
			(stroke
				(width 0.1)
				(type default)
			)
			(layer "F.Fab")
		)
		(fp_line
			(start -0.67945 -0.305054)
			(end -0.12065 -0.305054)
			(stroke
				(width 0.1)
				(type default)
			)
			(layer "F.Fab")
		)
		(fp_line
			(start 0.67945 -0.3048)
			(end 0.67945 0.3048)
			(stroke
				(width 0.1)
				(type default)
			)
			(layer "F.Fab")
		)
		(fp_line
			(start 0.12065 -0.3048)
			(end 0.67945 -0.3048)
			(stroke
				(width 0.1)
				(type default)
			)
			(layer "F.Fab")
		)
		(fp_line
			(start 0.12065 -0.2794)
			(end 0.12065 -0.3048)
			(stroke
				(width 0.1)
				(type default)
			)
			(layer "F.Fab")
		)
		(fp_line
			(start -0.12065 -0.2794)
			(end 0.12065 -0.2794)
			(stroke
				(width 0.1)
				(type default)
			)
			(layer "F.Fab")
		)
		(fp_line
			(start 0.120396 0.2794)
			(end -0.12065 0.2794)
			(stroke
				(width 0.1)
				(type default)
			)
			(layer "F.Fab")
		)
		(fp_line
			(start -0.12065 0.2794)
			(end -0.12065 0.3048)
			(stroke
				(width 0.1)
				(type default)
			)
			(layer "F.Fab")
		)
		(fp_line
			(start 0.67945 0.3048)
			(end 0.120396 0.3048)
			(stroke
				(width 0.1)
				(type default)
			)
			(layer "F.Fab")
		)
		(fp_line
			(start 0.120396 0.3048)
			(end 0.120396 0.2794)
			(stroke
				(width 0.1)
				(type default)
			)
			(layer "F.Fab")
		)
		(fp_line
			(start -0.12065 0.3048)
			(end -0.67945 0.3048)
			(stroke
				(width 0.1)
				(type default)
			)
			(layer "F.Fab")
		)
		(fp_line
			(start -0.67945 0.3048)
			(end -0.67945 -0.305054)
			(stroke
				(width 0.1)
				(type default)
			)
			(layer "F.Fab")
		)
		(pad "1" smd circle
			(at -0.40005 0 90)
			(size 0 0)
			(layers "F.Cu" "F.Mask" "F.Paste")
			(net "P3V3_AUX")
		)
		(pad "2" smd circle
			(at 0.40005 0 90)
			(size 0 0)
			(layers "F.Cu" "F.Mask" "F.Paste")
			(net "USB_HUB2_TI_GRSTZ_MRP_PROG_FUNC1")
		)
	)
)
